# BASEBOARD_FAB2 (Tioga Pass) — schematic netlist excerpt (pin names and nets, part order shuffled) for the footprints in the layout excerpt that follows; sources: Cadence DE-HDL packaged netlist, KiCad conversion of Wiwynn_Tioga_Pass_MB.brd

R9G15  RES  20.0 1% CHIP  pkg 0402  page 167 : A = SMB_SENSOR_BMC_STBY_LVC3_SDA ; B = SMB_SENSOR_STBY_LVC3_SDA
R25W160  RES  1.00K 1% CHIP  pkg 0402  page 254 : A = P3V3_STBY ; B = JTAG_BMC_BUF_TDI
C5D33  CAP_A  22.0UF 4V 20% X6S  pkg 0603V  page 42 : A = PVCCMCP_CPU0 ; B = GND

(kicad_pcb
	(version 20260206)
	(generator "pcbnew")
	(generator_version "10.0")
	(general
		(thickness 1.6)
		(legacy_teardrops no)
	)
	(paper "A4")
	(title_block
		(title "Wiwynn_Tioga_Pass_MB.brd")
		(comment 1 "Tioga Pass / footprints 1307-1309 of 4770")
	)
	(layers
		(0 "F.Cu" signal "TOP")
		(4 "In1.Cu" signal "L2GND")
		(6 "In2.Cu" signal "L3")
		(8 "In3.Cu" signal "L4GND")
		(10 "In4.Cu" signal "L5")
		(12 "In5.Cu" signal "L6GND")
		(14 "In6.Cu" signal "L7VCC")
		(16 "In7.Cu" signal "L8VCC")
		(18 "In8.Cu" signal "L9GND")
		(20 "In9.Cu" signal "L10")
		(22 "In10.Cu" signal "L11GND")
		(24 "In11.Cu" signal "L12")
		(26 "In12.Cu" signal "L13GND")
		(2 "B.Cu" signal "BOTTOM")
		(9 "F.Adhes" user "F.Adhesive")
		(11 "B.Adhes" user "B.Adhesive")
		(13 "F.Paste" user "Package Geometry/Pastemask Top")
		(15 "B.Paste" user "Package Geometry/Pastemask Bottom")
		(5 "F.SilkS" user "Ref Des/Silkscreen Top")
		(7 "B.SilkS" user "Ref Des/Silkscreen Bottom")
		(1 "F.Mask" user "Board Geometry/Soldermask Top")
		(3 "B.Mask" user "Board Geometry/Soldermask Bottom")
		(17 "Dwgs.User" user "User.Drawings")
		(19 "Cmts.User" user "User.Comments")
		(21 "Eco1.User" user "User.Eco1")
		(23 "Eco2.User" user "User.Eco2")
		(25 "Edge.Cuts" user "Board Geometry/Outline")
		(27 "Margin" user)
		(31 "F.CrtYd" user "Package Geometry/Place Bound Top")
		(29 "B.CrtYd" user "Package Geometry/Place Bound Bottom")
		(35 "F.Fab" user "Ref Des/Assembly Top")
		(33 "B.Fab" user "Ref Des/Assembly Bottom")
	)
	(footprint ""
		(layer "F.Cu")
		(at 420.1414 -18.7452)
		(property "Reference" "R9G15"
			(at 0 0 0)
			(layer "F.SilkS")
			(hide yes)
			(effects
				(font
					(size 1.27 1.27)
				)
			)
		)
		(property "Value" ""
			(at 0 0 0)
			(layer "F.Fab")
			(effects
				(font
					(size 1.27 1.27)
				)
			)
		)
		(duplicate_pad_numbers_are_jumpers no)
		(fp_poly
			(pts
				(xy -0.2794 -0.1016) (xy 0.2794 -0.1016) (xy 0.2794 0.9906) (xy -0.2794 0.9906)
			)
			(stroke
				(width 0)
				(type default)
			)
			(fill no)
			(layer "F.CrtYd")
		)
		(fp_line
			(start -0.2794 -0.1016)
			(end -0.2794 0.9906)
			(stroke
				(width 0.1)
				(type default)
			)
			(layer "F.Fab")
		)
		(fp_line
			(start -0.2794 0.9906)
			(end 0.2794 0.9906)
			(stroke
				(width 0.1)
				(type default)
			)
			(layer "F.Fab")
		)
		(fp_line
			(start 0.2794 -0.1016)
			(end -0.2794 -0.1016)
			(stroke
				(width 0.1)
				(type default)
			)
			(layer "F.Fab")
		)
		(fp_line
			(start 0.2794 0.9906)
			(end 0.2794 -0.1016)
			(stroke
				(width 0.1)
				(type default)
			)
			(layer "F.Fab")
		)
		(pad "1" smd rect
			(at 0 0)
			(size 0.508 0.508)
			(layers "F.Cu" "F.Mask" "F.Paste")
			(net "SMB_SENSOR_BMC_STBY_LVC3_SDA")
		)
		(pad "2" smd rect
			(at 0 0.889)
			(size 0.508 0.508)
			(layers "F.Cu" "F.Mask" "F.Paste")
			(net "SMB_SENSOR_STBY_LVC3_SDA")
		)
		(zone
			(layer "F.Cu")
			(hatch none 0.5)
			(connect_pads
				(clearance 0)
			)
			(min_thickness 0.25)
			(keepout
				(tracks allowed)
				(vias not_allowed)
				(pads allowed)
				(copperpour not_allowed)
				(footprints allowed)
			)
			(placement
				(enabled no)
				(sheetname "")
			)
			(fill
				(thermal_gap 0.5)
				(thermal_bridge_width 0.5)
				(island_removal_mode 0)
			)
			(polygon
				(pts
					(xy 419.8874 -18.4912) (xy 420.3954 -18.4912) (xy 420.3954 -18.1102) (xy 419.8874 -18.1102)
				)
			)
		)
		(zone
			(layer "F.Cu")
			(hatch none 0.5)
			(connect_pads
				(clearance 0)
			)
			(min_thickness 0.25)
			(keepout
				(tracks not_allowed)
				(vias allowed)
				(pads allowed)
				(copperpour not_allowed)
				(footprints allowed)
			)
			(placement
				(enabled no)
				(sheetname "")
			)
			(fill
				(thermal_gap 0.5)
				(thermal_bridge_width 0.5)
				(island_removal_mode 0)
			)
			(polygon
				(pts
					(xy 419.8874 -18.1102) (xy 420.3954 -18.1102) (xy 420.3954 -18.4912) (xy 419.8874 -18.4912)
				)
			)
		)
	)
	(footprint ""
		(layer "F.Cu")
		(at 440.817 -143.002 90)
		(property "Reference" "R25W160"
			(at -0.8382 -0.67818 90)
			(unlocked yes)
			(layer "F.SilkS")
			(effects
				(font
					(size 0.4064 0.254)
					(thickness 0.1524)
				)
				(justify left)
			)
		)
		(property "Value" ""
			(at 0 0 90)
			(layer "F.Fab")
			(effects
				(font
					(size 1.27 1.27)
				)
			)
		)
		(duplicate_pad_numbers_are_jumpers no)
		(fp_poly
			(pts
				(xy -0.2794 -0.1016) (xy 0.2794 -0.1016) (xy 0.2794 0.9906) (xy -0.2794 0.9906)
			)
			(stroke
				(width 0)
				(type default)
			)
			(fill no)
			(layer "F.CrtYd")
		)
		(fp_line
			(start 0.2794 -0.1016)
			(end -0.2794 -0.1016)
			(stroke
				(width 0.1)
				(type default)
			)
			(layer "F.Fab")
		)
		(fp_line
			(start -0.2794 -0.1016)
			(end -0.2794 0.9906)
			(stroke
				(width 0.1)
				(type default)
			)
			(layer "F.Fab")
		)
		(fp_line
			(start 0.2794 0.9906)
			(end 0.2794 -0.1016)
			(stroke
				(width 0.1)
				(type default)
			)
			(layer "F.Fab")
		)
		(fp_line
			(start -0.2794 0.9906)
			(end 0.2794 0.9906)
			(stroke
				(width 0.1)
				(type default)
			)
			(layer "F.Fab")
		)
		(pad "1" smd rect
			(at 0 0 90)
			(size 0.508 0.508)
			(layers "F.Cu" "F.Mask" "F.Paste")
			(net "P3V3_STBY")
		)
		(pad "2" smd rect
			(at 0 0.889 90)
			(size 0.508 0.508)
			(layers "F.Cu" "F.Mask" "F.Paste")
			(net "JTAG_BMC_BUF_TDI")
		)
		(zone
			(layer "F.Cu")
			(hatch none 0.5)
			(connect_pads
				(clearance 0)
			)
			(min_thickness 0.25)
			(keepout
				(tracks allowed)
				(vias not_allowed)
				(pads allowed)
				(copperpour not_allowed)
				(footprints allowed)
			)
			(placement
				(enabled no)
				(sheetname "")
			)
			(fill
				(thermal_gap 0.5)
				(thermal_bridge_width 0.5)
				(island_removal_mode 0)
			)
			(polygon
				(pts
					(xy 441.071 -142.748) (xy 441.071 -143.256) (xy 441.452 -143.256) (xy 441.452 -142.748)
				)
			)
		)
		(zone
			(layer "F.Cu")
			(hatch none 0.5)
			(connect_pads
				(clearance 0)
			)
			(min_thickness 0.25)
			(keepout
				(tracks not_allowed)
				(vias allowed)
				(pads allowed)
				(copperpour not_allowed)
				(footprints allowed)
			)
			(placement
				(enabled no)
				(sheetname "")
			)
			(fill
				(thermal_gap 0.5)
				(thermal_bridge_width 0.5)
				(island_removal_mode 0)
			)
			(polygon
				(pts
					(xy 441.452 -142.748) (xy 441.452 -143.256) (xy 441.071 -143.256) (xy 441.071 -142.748)
				)
			)
		)
	)
	(footprint ""
		(layer "F.Cu")
		(at 269.409672 -77.636116)
		(property "Reference" "C5D33"
			(at 0 0 0)
			(layer "F.SilkS")
			(hide yes)
			(effects
				(font
					(size 1.27 1.27)
				)
			)
		)
		(property "Value" ""
			(at 0 0 0)
			(layer "F.Fab")
			(effects
				(font
					(size 1.27 1.27)
				)
			)
		)
		(duplicate_pad_numbers_are_jumpers no)
		(fp_poly
			(pts
				(xy -0.4953 -0.2032) (xy 0.4953 -0.2032) (xy 0.4953 1.6002) (xy -0.4953 1.6002)
			)
			(stroke
				(width 0)
				(type default)
			)
			(fill no)
			(layer "F.CrtYd")
		)
		(fp_line
			(start -0.4953 -0.2032)
			(end 0.4953 -0.2032)
			(stroke
				(width 0.1)
				(type default)
			)
			(layer "F.Fab")
		)
		(fp_line
			(start -0.4953 1.6002)
			(end -0.4953 -0.2032)
			(stroke
				(width 0.1)
				(type default)
			)
			(layer "F.Fab")
		)
		(fp_line
			(start 0.4953 -0.2032)
			(end 0.4953 1.6002)
			(stroke
				(width 0.1)
				(type default)
			)
			(layer "F.Fab")
		)
		(fp_line
			(start 0.4953 1.6002)
			(end -0.4953 1.6002)
			(stroke
				(width 0.1)
				(type default)
			)
			(layer "F.Fab")
		)
		(pad "1" smd rect
			(at 0 0)
			(size 0.762 0.889)
			(layers "F.Cu" "F.Mask" "F.Paste")
			(net "PVCCMCP_CPU0")
		)
		(pad "2" smd rect
			(at 0 1.397)
			(size 0.762 0.889)
			(layers "F.Cu" "F.Mask" "F.Paste")
			(net "GND")
		)
		(zone
			(layer "F.Cu")
			(hatch none 0.5)
			(connect_pads
				(clearance 0)
			)
			(min_thickness 0.25)
			(keepout
				(tracks not_allowed)
				(vias allowed)
				(pads allowed)
				(copperpour not_allowed)
				(footprints allowed)
			)
			(placement
				(enabled no)
				(sheetname "")
			)
			(fill
				(thermal_gap 0.5)
				(thermal_bridge_width 0.5)
				(island_removal_mode 0)
			)
			(polygon
				(pts
					(xy 269.028672 -77.191616) (xy 269.790672 -77.191616) (xy 269.790672 -76.683616) (xy 269.028672 -76.683616)
				)
			)
		)
	)
)
